# T6G (Grand Teton) — schematic netlist excerpt (pin names and nets, part order shuffled) for the footprints in the layout excerpt that follows; sources: Cadence DE-HDL packaged netlist, KiCad conversion of 04192023_DAF0TMB3IC0_F0TG_MB_C_brd_V02_OCP.brd

R3807  Q_RES  0 5% CHIP  pkg 0402LF  page 140 : A = P3V3_OCP_UV_2_R1 ; B = P3V3_OCP_UV_2
C578  Q_CAP  0.1UF 10V 10% X7S  pkg C0201  page 279 : A = P0V9_CPU0_RT_2D ; B = GND
R785  Q_RES  4.7K 5% CHIP  pkg 0201LF  page 331 : A = TEST0_RT_CPU1_P1 ; B = GND

(kicad_pcb
	(version 20260206)
	(generator "pcbnew")
	(generator_version "10.0")
	(general
		(thickness 1.6)
		(legacy_teardrops no)
	)
	(paper "A4")
	(title_block
		(title "04192023_DAF0TMB3IC0_F0TG_MB_C_brd_V02_OCP.brd")
		(comment 1 "Grand Teton / footprints 6935-6937 of 8354")
	)
	(layers
		(0 "F.Cu" signal "TOP")
		(4 "In1.Cu" signal "GND")
		(6 "In2.Cu" signal "IN1")
		(8 "In3.Cu" signal "GND1")
		(10 "In4.Cu" signal "IN2")
		(12 "In5.Cu" signal "GND2")
		(14 "In6.Cu" signal "IN3")
		(16 "In7.Cu" signal "GND3")
		(18 "In8.Cu" signal "VCC")
		(20 "In9.Cu" signal "VCC1")
		(22 "In10.Cu" signal "GND4")
		(24 "In11.Cu" signal "IN4")
		(26 "In12.Cu" signal "GND5")
		(28 "In13.Cu" signal "IN5")
		(30 "In14.Cu" signal "GND6")
		(32 "In15.Cu" signal "IN6")
		(34 "In16.Cu" signal "GND7")
		(2 "B.Cu" signal "BOTTOM")
		(9 "F.Adhes" user "F.Adhesive")
		(11 "B.Adhes" user "B.Adhesive")
		(13 "F.Paste" user "Package Geometry/Pastemask Top")
		(15 "B.Paste" user "Package Geometry/Pastemask Bottom")
		(5 "F.SilkS" user "Ref Des/Silkscreen Top")
		(7 "B.SilkS" user "Ref Des/Silkscreen Bottom")
		(1 "F.Mask" user "Board Geometry/Soldermask Top")
		(3 "B.Mask" user "Board Geometry/Soldermask Bottom")
		(17 "Dwgs.User" user "User.Drawings")
		(19 "Cmts.User" user "User.Comments")
		(21 "Eco1.User" user "User.Eco1")
		(23 "Eco2.User" user "User.Eco2")
		(25 "Edge.Cuts" user "Board Geometry/Outline")
		(27 "Margin" user)
		(31 "F.CrtYd" user "Package Geometry/Place Bound Top")
		(29 "B.CrtYd" user "Package Geometry/Place Bound Bottom")
		(35 "F.Fab" user "Ref Des/Assembly Top")
		(33 "B.Fab" user "Ref Des/Assembly Bottom")
	)
	(footprint ""
		(layer "B.Cu")
		(at 75.7936 -385.58216 180)
		(property "Reference" "R785"
			(at 0 0 0)
			(layer "B.SilkS")
			(hide yes)
			(effects
				(font
					(size 1.27 1.27)
				)
				(justify mirror)
			)
		)
		(property "Value" ""
			(at 0 0 0)
			(layer "B.Fab")
			(effects
				(font
					(size 1.27 1.27)
				)
				(justify mirror)
			)
		)
		(duplicate_pad_numbers_are_jumpers no)
		(fp_line
			(start 0.32512 0.175006)
			(end 0.32512 -0.175006)
			(stroke
				(width 0.1)
				(type default)
			)
			(layer "B.Fab")
		)
		(fp_line
			(start 0.32512 -0.175006)
			(end -0.32512 -0.175006)
			(stroke
				(width 0.1)
				(type default)
			)
			(layer "B.Fab")
		)
		(fp_line
			(start -0.32512 0.175006)
			(end 0.32512 0.175006)
			(stroke
				(width 0.1)
				(type default)
			)
			(layer "B.Fab")
		)
		(fp_line
			(start -0.32512 -0.175006)
			(end -0.32512 0.175006)
			(stroke
				(width 0.1)
				(type default)
			)
			(layer "B.Fab")
		)
		(pad "1" smd rect
			(at 0.2667 0)
			(size 0.3048 0.381)
			(layers "B.Cu" "B.Mask" "B.Paste")
			(net "TEST0_RT_CPU1_P1")
		)
		(pad "2" smd rect
			(at -0.2667 0 180)
			(size 0.3048 0.381)
			(layers "B.Cu" "B.Mask" "B.Paste")
			(net "GND")
		)
	)
	(footprint ""
		(layer "B.Cu")
		(at 315.378338 -395.148562 90)
		(property "Reference" "C578"
			(at 0 0 90)
			(layer "B.SilkS")
			(hide yes)
			(effects
				(font
					(size 1.27 1.27)
				)
				(justify mirror)
			)
		)
		(property "Value" ""
			(at 0 0 90)
			(layer "B.Fab")
			(effects
				(font
					(size 1.27 1.27)
				)
				(justify mirror)
			)
		)
		(duplicate_pad_numbers_are_jumpers no)
		(fp_line
			(start 0.299974 -0.150114)
			(end -0.299974 -0.150114)
			(stroke
				(width 0.1)
				(type default)
			)
			(layer "B.Fab")
		)
		(fp_line
			(start -0.299974 -0.150114)
			(end -0.299974 0.150114)
			(stroke
				(width 0.1)
				(type default)
			)
			(layer "B.Fab")
		)
		(fp_line
			(start 0.299974 0.150114)
			(end 0.299974 -0.150114)
			(stroke
				(width 0.1)
				(type default)
			)
			(layer "B.Fab")
		)
		(fp_line
			(start -0.299974 0.150114)
			(end 0.299974 0.150114)
			(stroke
				(width 0.1)
				(type default)
			)
			(layer "B.Fab")
		)
		(pad "1" smd rect
			(at 0.2667 0 270)
			(size 0.3048 0.381)
			(layers "B.Cu" "B.Mask" "B.Paste")
			(net "P0V9_CPU0_RT_2D")
		)
		(pad "2" smd rect
			(at -0.2667 0 270)
			(size 0.3048 0.381)
			(layers "B.Cu" "B.Mask" "B.Paste")
			(net "GND")
		)
	)
	(footprint ""
		(layer "B.Cu")
		(at 94.435422 -60.820808)
		(property "Reference" "R3807"
			(at 0 0 0)
			(layer "B.SilkS")
			(hide yes)
			(effects
				(font
					(size 1.27 1.27)
				)
				(justify mirror)
			)
		)
		(property "Value" ""
			(at 0 0 0)
			(layer "B.Fab")
			(effects
				(font
					(size 1.27 1.27)
				)
				(justify mirror)
			)
		)
		(duplicate_pad_numbers_are_jumpers no)
		(fp_line
			(start -0.7874 -0.4064)
			(end -0.7874 0.4064)
			(stroke
				(width 0.1524)
				(type default)
			)
			(layer "B.SilkS")
		)
		(fp_line
			(start -0.7874 0.4064)
			(end 0.7874 0.4064)
			(stroke
				(width 0.1524)
				(type default)
			)
			(layer "B.SilkS")
		)
		(fp_line
			(start 0.7874 -0.4064)
			(end -0.7874 -0.4064)
			(stroke
				(width 0.1524)
				(type default)
			)
			(layer "B.SilkS")
		)
		(fp_line
			(start 0.7874 0.4064)
			(end 0.7874 -0.4064)
			(stroke
				(width 0.1524)
				(type default)
			)
			(layer "B.SilkS")
		)
		(fp_line
			(start -0.67945 -0.3048)
			(end -0.67945 0.3048)
			(stroke
				(width 0.1)
				(type default)
			)
			(layer "B.Fab")
		)
		(fp_line
			(start -0.67945 0.3048)
			(end -0.120396 0.3048)
			(stroke
				(width 0.1)
				(type default)
			)
			(layer "B.Fab")
		)
		(fp_line
			(start -0.12065 -0.3048)
			(end -0.67945 -0.3048)
			(stroke
				(width 0.1)
				(type default)
			)
			(layer "B.Fab")
		)
		(fp_line
			(start -0.12065 -0.2794)
			(end -0.12065 -0.3048)
			(stroke
				(width 0.1)
				(type default)
			)
			(layer "B.Fab")
		)
		(fp_line
			(start -0.120396 0.2794)
			(end 0.12065 0.2794)
			(stroke
				(width 0.1)
				(type default)
			)
			(layer "B.Fab")
		)
		(fp_line
			(start -0.120396 0.3048)
			(end -0.120396 0.2794)
			(stroke
				(width 0.1)
				(type default)
			)
			(layer "B.Fab")
		)
		(fp_line
			(start 0.12065 -0.305054)
			(end 0.12065 -0.2794)
			(stroke
				(width 0.1)
				(type default)
			)
			(layer "B.Fab")
		)
		(fp_line
			(start 0.12065 -0.2794)
			(end -0.12065 -0.2794)
			(stroke
				(width 0.1)
				(type default)
			)
			(layer "B.Fab")
		)
		(fp_line
			(start 0.12065 0.2794)
			(end 0.12065 0.3048)
			(stroke
				(width 0.1)
				(type default)
			)
			(layer "B.Fab")
		)
		(fp_line
			(start 0.12065 0.3048)
			(end 0.67945 0.3048)
			(stroke
				(width 0.1)
				(type default)
			)
			(layer "B.Fab")
		)
		(fp_line
			(start 0.67945 -0.305054)
			(end 0.12065 -0.305054)
			(stroke
				(width 0.1)
				(type default)
			)
			(layer "B.Fab")
		)
		(fp_line
			(start 0.67945 0.3048)
			(end 0.67945 -0.305054)
			(stroke
				(width 0.1)
				(type default)
			)
			(layer "B.Fab")
		)
		(pad "1" smd circle
			(at 0.40005 0 180)
			(size 0 0)
			(layers "B.Cu" "B.Mask" "B.Paste")
			(net "P3V3_OCP_UV_2_R1")
		)
		(pad "2" smd circle
			(at -0.40005 0 180)
			(size 0 0)
			(layers "B.Cu" "B.Mask" "B.Paste")
			(net "P3V3_OCP_UV_2")
		)
	)
)
